(kicad_pcb
	(version 20260206)
	(generator "pcbnew")
	(generator_version "10.0")
	(general
		(thickness 1.6)
		(legacy_teardrops no)
	)
	(paper "A4")
	(title_block
		(title "panther-plus-userver — 13130-1b_20150205.brd")
		(comment 1 "Honey Badger (Wiwynn) / footprints 1366-1373 of 1509")
	)
	(layers
		(0 "F.Cu" signal "TOP")
		(4 "In1.Cu" signal "L2")
		(6 "In2.Cu" signal "L3")
		(8 "In3.Cu" signal "L4")
		(10 "In4.Cu" signal "L5")
		(12 "In5.Cu" signal "L6")
		(14 "In6.Cu" signal "L7")
		(16 "In7.Cu" signal "L8")
		(18 "In8.Cu" signal "L9")
		(20 "In9.Cu" signal "L10")
		(22 "In10.Cu" signal "L11")
		(2 "B.Cu" signal "BOTTOM")
		(9 "F.Adhes" user "F.Adhesive")
		(11 "B.Adhes" user "B.Adhesive")
		(13 "F.Paste" user "Package Geometry/Pastemask Top")
		(15 "B.Paste" user "Package Geometry/Pastemask Bottom")
		(5 "F.SilkS" user "Ref Des/Silkscreen Top")
		(7 "B.SilkS" user "Ref Des/Silkscreen Bottom")
		(1 "F.Mask" user "Board Geometry/Soldermask Top")
		(3 "B.Mask" user "Board Geometry/Soldermask Bottom")
		(17 "Dwgs.User" user "User.Drawings")
		(19 "Cmts.User" user "User.Comments")
		(21 "Eco1.User" user "User.Eco1")
		(23 "Eco2.User" user "User.Eco2")
		(25 "Edge.Cuts" user "Board Geometry/Outline")
		(27 "Margin" user)
		(31 "F.CrtYd" user "Package Geometry/Place Bound Top")
		(29 "B.CrtYd" user "Package Geometry/Place Bound Bottom")
		(35 "F.Fab" user "Ref Des/Assembly Top")
		(33 "B.Fab" user "Ref Des/Assembly Bottom")
	)
	(footprint ""
		(layer "B.Cu")
		(at 77.343 -37.084)
		(property "Reference" "R332"
			(at 0 0 0)
			(layer "B.SilkS")
			(hide yes)
			(effects
				(font
					(size 1.27 1.27)
				)
				(justify mirror)
			)
		)
		(property "Value" "1KR2F-3-GP"
			(at -0.064008 -3.993896 0)
			(unlocked yes)
			(layer "B.Fab")
			(hide yes)
			(effects
				(font
					(size 1.016 1.016)
					(thickness 0.1524)
				)
				(justify mirror)
			)
		)
		(property "Device Type" "R402H16"
			(at -0.064008 -5.517896 0)
			(unlocked yes)
			(layer "B.Fab")
			(hide yes)
			(effects
				(font
					(size 1.016 1.016)
					(thickness 0.1524)
				)
				(justify mirror)
			)
		)
		(duplicate_pad_numbers_are_jumpers no)
		(fp_rect
			(start 0.381 0.8382)
			(end -0.381 -0.8382)
			(stroke
				(width 0)
				(type default)
			)
			(fill no)
			(layer "B.CrtYd")
		)
		(fp_rect
			(start 0.381 0.8382)
			(end -0.381 -0.8382)
			(stroke
				(width 0)
				(type default)
			)
			(fill no)
			(layer "B.Fab")
		)
		(pad "1" smd custom
			(at 0 -0.4318 180)
			(size 0.127 0.127)
			(layers "B.Cu" "B.Mask" "B.Paste")
			(net "PMU_SUS_CLK")
			(options
				(clearance outline)
				(anchor circle)
			)
			(primitives
				(gr_poly
					(pts
						(arc
							(start -0.2032 0.2794)
							(mid -0.239121 0.264521)
							(end -0.254 0.2286)
						)
						(arc
							(start -0.254 -0.2286)
							(mid -0.239121 -0.264521)
							(end -0.2032 -0.2794)
						)
						(arc
							(start 0.2032 -0.2794)
							(mid 0.239121 -0.264521)
							(end 0.254 -0.2286)
						)
						(arc
							(start 0.254 0.2286)
							(mid 0.239121 0.264521)
							(end 0.2032 0.2794)
						)
					)
					(width 0)
					(fill yes)
				)
			)
		)
		(pad "2" smd custom
			(at 0 0.4318 180)
			(size 0.127 0.127)
			(layers "B.Cu" "B.Mask" "B.Paste")
			(net "GND")
			(options
				(clearance outline)
				(anchor circle)
			)
			(primitives
				(gr_poly
					(pts
						(arc
							(start -0.2032 0.2794)
							(mid -0.239121 0.264521)
							(end -0.254 0.2286)
						)
						(arc
							(start -0.254 -0.2286)
							(mid -0.239121 -0.264521)
							(end -0.2032 -0.2794)
						)
						(arc
							(start 0.2032 -0.2794)
							(mid 0.239121 -0.264521)
							(end 0.254 -0.2286)
						)
						(arc
							(start 0.254 0.2286)
							(mid 0.239121 0.264521)
							(end 0.2032 0.2794)
						)
					)
					(width 0)
					(fill yes)
				)
			)
		)
	)
	(footprint ""
		(layer "B.Cu")
		(at 4.826 -45.085)
		(property "Reference" "LED15"
			(at 0 0 0)
			(layer "B.SilkS")
			(hide yes)
			(effects
				(font
					(size 1.27 1.27)
				)
				(justify mirror)
			)
		)
		(property "Value" "LED-YG-51-GP"
			(at 2.6924 -1.4224 0)
			(unlocked yes)
			(layer "B.Fab")
			(hide yes)
			(effects
				(font
					(size 1.016 1.016)
					(thickness 0.1524)
				)
				(justify mirror)
			)
		)
		(property "Device Type" "LED1608AKH40"
			(at 2.6924 -2.9464 0)
			(unlocked yes)
			(layer "B.Fab")
			(hide yes)
			(effects
				(font
					(size 1.016 1.016)
					(thickness 0.1524)
				)
				(justify mirror)
			)
		)
		(duplicate_pad_numbers_are_jumpers no)
		(fp_line
			(start 0.5334 1.3081)
			(end -0.5334 1.3081)
			(stroke
				(width 0.254)
				(type default)
			)
			(layer "B.SilkS")
		)
		(fp_rect
			(start 0.6604 1.1811)
			(end -0.6604 -1.1811)
			(stroke
				(width 0)
				(type default)
			)
			(fill no)
			(layer "B.CrtYd")
		)
		(fp_rect
			(start 0.6604 1.1811)
			(end -0.6604 -1.1811)
			(stroke
				(width 0)
				(type default)
			)
			(fill no)
			(layer "B.Fab")
		)
		(pad "A" smd rect
			(at 0 -0.652526 180)
			(size 1.0668 0.8128)
			(layers "B.Cu" "B.Mask" "B.Paste")
			(net "LED_NGFF_DAS_R")
		)
		(pad "K" smd rect
			(at 0 0.652526 180)
			(size 1.0668 0.8128)
			(layers "B.Cu" "B.Mask" "B.Paste")
			(net "LED_NGFF_DAS")
		)
	)
	(footprint ""
		(layer "B.Cu")
		(at 45.466 -12.7)
		(property "Reference" "C263"
			(at 0 0 0)
			(layer "B.SilkS")
			(hide yes)
			(effects
				(font
					(size 1.27 1.27)
				)
				(justify mirror)
			)
		)
		(property "Value" "SCD1U16V2KX-3GP"
			(at -1.1811 -2.7051 0)
			(unlocked yes)
			(layer "B.Fab")
			(hide yes)
			(effects
				(font
					(size 1.016 1.016)
					(thickness 0.1524)
				)
				(justify mirror)
			)
		)
		(property "Device Type" "C402H22"
			(at -1.1811 -4.2291 0)
			(unlocked yes)
			(layer "B.Fab")
			(hide yes)
			(effects
				(font
					(size 1.016 1.016)
					(thickness 0.1524)
				)
				(justify mirror)
			)
		)
		(duplicate_pad_numbers_are_jumpers no)
		(fp_rect
			(start 0.381 0.7366)
			(end -0.381 -0.7366)
			(stroke
				(width 0)
				(type default)
			)
			(fill no)
			(layer "B.CrtYd")
		)
		(fp_rect
			(start 0.381 0.7366)
			(end -0.381 -0.7366)
			(stroke
				(width 0)
				(type default)
			)
			(fill no)
			(layer "B.Fab")
		)
		(pad "1" smd custom
			(at 0 -0.4572 180)
			(size 0.1143 0.1143)
			(layers "B.Cu" "B.Mask" "B.Paste")
			(net "P2E_CPU_SAS_C_TX_DN4")
			(options
				(clearance outline)
				(anchor circle)
			)
			(primitives
				(gr_poly
					(pts
						(arc
							(start -0.254 0.1778)
							(mid -0.239121 0.213721)
							(end -0.2032 0.2286)
						)
						(arc
							(start 0.2032 0.2286)
							(mid 0.239121 0.213721)
							(end 0.254 0.1778)
						)
						(arc
							(start 0.254 -0.1778)
							(mid 0.239121 -0.213721)
							(end 0.2032 -0.2286)
						)
						(arc
							(start -0.2032 -0.2286)
							(mid -0.239121 -0.213721)
							(end -0.254 -0.1778)
						)
					)
					(width 0)
					(fill yes)
				)
			)
		)
		(pad "2" smd custom
			(at 0 0.4572 180)
			(size 0.1143 0.1143)
			(layers "B.Cu" "B.Mask" "B.Paste")
			(net "P2E_CPU_SAS_TX_DN4")
			(options
				(clearance outline)
				(anchor circle)
			)
			(primitives
				(gr_poly
					(pts
						(arc
							(start -0.254 0.1778)
							(mid -0.239121 0.213721)
							(end -0.2032 0.2286)
						)
						(arc
							(start 0.2032 0.2286)
							(mid 0.239121 0.213721)
							(end 0.254 0.1778)
						)
						(arc
							(start 0.254 -0.1778)
							(mid 0.239121 -0.213721)
							(end 0.2032 -0.2286)
						)
						(arc
							(start -0.2032 -0.2286)
							(mid -0.239121 -0.213721)
							(end -0.254 -0.1778)
						)
					)
					(width 0)
					(fill yes)
				)
			)
		)
	)
	(footprint ""
		(layer "B.Cu")
		(at 86.233 -63.246)
		(property "Reference" "R276"
			(at 0 0 0)
			(layer "B.SilkS")
			(hide yes)
			(effects
				(font
					(size 1.27 1.27)
				)
				(justify mirror)
			)
		)
		(property "Value" "1KR2F-3-GP"
			(at -0.064008 -3.993896 0)
			(unlocked yes)
			(layer "B.Fab")
			(hide yes)
			(effects
				(font
					(size 1.016 1.016)
					(thickness 0.1524)
				)
				(justify mirror)
			)
		)
		(property "Device Type" "R402H16"
			(at -0.064008 -5.517896 0)
			(unlocked yes)
			(layer "B.Fab")
			(hide yes)
			(effects
				(font
					(size 1.016 1.016)
					(thickness 0.1524)
				)
				(justify mirror)
			)
		)
		(duplicate_pad_numbers_are_jumpers no)
		(fp_rect
			(start 0.381 0.8382)
			(end -0.381 -0.8382)
			(stroke
				(width 0)
				(type default)
			)
			(fill no)
			(layer "B.CrtYd")
		)
		(fp_rect
			(start 0.381 0.8382)
			(end -0.381 -0.8382)
			(stroke
				(width 0)
				(type default)
			)
			(fill no)
			(layer "B.Fab")
		)
		(pad "1" smd custom
			(at 0 -0.4318 180)
			(size 0.127 0.127)
			(layers "B.Cu" "B.Mask" "B.Paste")
			(net "P3V3_STBY")
			(options
				(clearance outline)
				(anchor circle)
			)
			(primitives
				(gr_poly
					(pts
						(arc
							(start -0.2032 0.2794)
							(mid -0.239121 0.264521)
							(end -0.254 0.2286)
						)
						(arc
							(start -0.254 -0.2286)
							(mid -0.239121 -0.264521)
							(end -0.2032 -0.2794)
						)
						(arc
							(start 0.2032 -0.2794)
							(mid 0.239121 -0.264521)
							(end 0.254 -0.2286)
						)
						(arc
							(start 0.254 0.2286)
							(mid 0.239121 0.264521)
							(end 0.2032 0.2794)
						)
					)
					(width 0)
					(fill yes)
				)
			)
		)
		(pad "2" smd custom
			(at 0 0.4318 180)
			(size 0.127 0.127)
			(layers "B.Cu" "B.Mask" "B.Paste")
			(net "PROCESSOR_HOT_LVC#")
			(options
				(clearance outline)
				(anchor circle)
			)
			(primitives
				(gr_poly
					(pts
						(arc
							(start -0.2032 0.2794)
							(mid -0.239121 0.264521)
							(end -0.254 0.2286)
						)
						(arc
							(start -0.254 -0.2286)
							(mid -0.239121 -0.264521)
							(end -0.2032 -0.2794)
						)
						(arc
							(start 0.2032 -0.2794)
							(mid 0.239121 -0.264521)
							(end 0.254 -0.2286)
						)
						(arc
							(start 0.254 0.2286)
							(mid 0.239121 0.264521)
							(end 0.2032 0.2794)
						)
					)
					(width 0)
					(fill yes)
				)
			)
		)
	)
	(footprint ""
		(layer "B.Cu")
		(at 41.468802 -12.7)
		(property "Reference" "C265"
			(at 0 0 0)
			(layer "B.SilkS")
			(hide yes)
			(effects
				(font
					(size 1.27 1.27)
				)
				(justify mirror)
			)
		)
		(property "Value" "SCD1U16V2KX-3GP"
			(at -1.1811 -2.7051 0)
			(unlocked yes)
			(layer "B.Fab")
			(hide yes)
			(effects
				(font
					(size 1.016 1.016)
					(thickness 0.1524)
				)
				(justify mirror)
			)
		)
		(property "Device Type" "C402H22"
			(at -1.1811 -4.2291 0)
			(unlocked yes)
			(layer "B.Fab")
			(hide yes)
			(effects
				(font
					(size 1.016 1.016)
					(thickness 0.1524)
				)
				(justify mirror)
			)
		)
		(duplicate_pad_numbers_are_jumpers no)
		(fp_rect
			(start 0.381 0.7366)
			(end -0.381 -0.7366)
			(stroke
				(width 0)
				(type default)
			)
			(fill no)
			(layer "B.CrtYd")
		)
		(fp_rect
			(start 0.381 0.7366)
			(end -0.381 -0.7366)
			(stroke
				(width 0)
				(type default)
			)
			(fill no)
			(layer "B.Fab")
		)
		(pad "1" smd custom
			(at 0 -0.4572 180)
			(size 0.1143 0.1143)
			(layers "B.Cu" "B.Mask" "B.Paste")
			(net "P2E_CPU_SAS_C_TX_DN5")
			(options
				(clearance outline)
				(anchor circle)
			)
			(primitives
				(gr_poly
					(pts
						(arc
							(start -0.254 0.1778)
							(mid -0.239121 0.213721)
							(end -0.2032 0.2286)
						)
						(arc
							(start 0.2032 0.2286)
							(mid 0.239121 0.213721)
							(end 0.254 0.1778)
						)
						(arc
							(start 0.254 -0.1778)
							(mid 0.239121 -0.213721)
							(end 0.2032 -0.2286)
						)
						(arc
							(start -0.2032 -0.2286)
							(mid -0.239121 -0.213721)
							(end -0.254 -0.1778)
						)
					)
					(width 0)
					(fill yes)
				)
			)
		)
		(pad "2" smd custom
			(at 0 0.4572 180)
			(size 0.1143 0.1143)
			(layers "B.Cu" "B.Mask" "B.Paste")
			(net "P2E_CPU_SAS_TX_DN5")
			(options
				(clearance outline)
				(anchor circle)
			)
			(primitives
				(gr_poly
					(pts
						(arc
							(start -0.254 0.1778)
							(mid -0.239121 0.213721)
							(end -0.2032 0.2286)
						)
						(arc
							(start 0.2032 0.2286)
							(mid 0.239121 0.213721)
							(end 0.254 0.1778)
						)
						(arc
							(start 0.254 -0.1778)
							(mid 0.239121 -0.213721)
							(end 0.2032 -0.2286)
						)
						(arc
							(start -0.2032 -0.2286)
							(mid -0.239121 -0.213721)
							(end -0.254 -0.1778)
						)
					)
					(width 0)
					(fill yes)
				)
			)
		)
	)
	(footprint ""
		(layer "B.Cu")
		(at 42.230802 -12.7)
		(property "Reference" "C264"
			(at 0 0 0)
			(layer "B.SilkS")
			(hide yes)
			(effects
				(font
					(size 1.27 1.27)
				)
				(justify mirror)
			)
		)
		(property "Value" "SCD1U16V2KX-3GP"
			(at -1.1811 -2.7051 0)
			(unlocked yes)
			(layer "B.Fab")
			(hide yes)
			(effects
				(font
					(size 1.016 1.016)
					(thickness 0.1524)
				)
				(justify mirror)
			)
		)
		(property "Device Type" "C402H22"
			(at -1.1811 -4.2291 0)
			(unlocked yes)
			(layer "B.Fab")
			(hide yes)
			(effects
				(font
					(size 1.016 1.016)
					(thickness 0.1524)
				)
				(justify mirror)
			)
		)
		(duplicate_pad_numbers_are_jumpers no)
		(fp_rect
			(start 0.381 0.7366)
			(end -0.381 -0.7366)
			(stroke
				(width 0)
				(type default)
			)
			(fill no)
			(layer "B.CrtYd")
		)
		(fp_rect
			(start 0.381 0.7366)
			(end -0.381 -0.7366)
			(stroke
				(width 0)
				(type default)
			)
			(fill no)
			(layer "B.Fab")
		)
		(pad "1" smd custom
			(at 0 -0.4572 180)
			(size 0.1143 0.1143)
			(layers "B.Cu" "B.Mask" "B.Paste")
			(net "P2E_CPU_SAS_C_TX_DP5")
			(options
				(clearance outline)
				(anchor circle)
			)
			(primitives
				(gr_poly
					(pts
						(arc
							(start -0.254 0.1778)
							(mid -0.239121 0.213721)
							(end -0.2032 0.2286)
						)
						(arc
							(start 0.2032 0.2286)
							(mid 0.239121 0.213721)
							(end 0.254 0.1778)
						)
						(arc
							(start 0.254 -0.1778)
							(mid 0.239121 -0.213721)
							(end 0.2032 -0.2286)
						)
						(arc
							(start -0.2032 -0.2286)
							(mid -0.239121 -0.213721)
							(end -0.254 -0.1778)
						)
					)
					(width 0)
					(fill yes)
				)
			)
		)
		(pad "2" smd custom
			(at 0 0.4572 180)
			(size 0.1143 0.1143)
			(layers "B.Cu" "B.Mask" "B.Paste")
			(net "P2E_CPU_SAS_TX_DP5")
			(options
				(clearance outline)
				(anchor circle)
			)
			(primitives
				(gr_poly
					(pts
						(arc
							(start -0.254 0.1778)
							(mid -0.239121 0.213721)
							(end -0.2032 0.2286)
						)
						(arc
							(start 0.2032 0.2286)
							(mid 0.239121 0.213721)
							(end 0.254 0.1778)
						)
						(arc
							(start 0.254 -0.1778)
							(mid 0.239121 -0.213721)
							(end 0.2032 -0.2286)
						)
						(arc
							(start -0.2032 -0.2286)
							(mid -0.239121 -0.213721)
							(end -0.254 -0.1778)
						)
					)
					(width 0)
					(fill yes)
				)
			)
		)
	)
	(footprint ""
		(layer "B.Cu")
		(at 100.289868 -36.353496 -90)
		(property "Reference" "C199"
			(at 0 0 90)
			(layer "B.SilkS")
			(hide yes)
			(effects
				(font
					(size 1.27 1.27)
				)
				(justify mirror)
			)
		)
		(property "Value" "SC2D2U10V2KX-GP"
			(at -1.1811 -2.7051 270)
			(unlocked yes)
			(layer "B.Fab")
			(hide yes)
			(effects
				(font
					(size 1.016 1.016)
					(thickness 0.1524)
				)
				(justify mirror)
			)
		)
		(property "Device Type" "C402H22"
			(at -1.1811 -4.2291 270)
			(unlocked yes)
			(layer "B.Fab")
			(hide yes)
			(effects
				(font
					(size 1.016 1.016)
					(thickness 0.1524)
				)
				(justify mirror)
			)
		)
		(duplicate_pad_numbers_are_jumpers no)
		(fp_rect
			(start 0.381 0.7366)
			(end -0.381 -0.7366)
			(stroke
				(width 0)
				(type default)
			)
			(fill no)
			(layer "B.CrtYd")
		)
		(fp_rect
			(start 0.381 0.7366)
			(end -0.381 -0.7366)
			(stroke
				(width 0)
				(type default)
			)
			(fill no)
			(layer "B.Fab")
		)
		(pad "1" smd custom
			(at 0 -0.4572 90)
			(size 0.1143 0.1143)
			(layers "B.Cu" "B.Mask" "B.Paste")
			(net "P1V0")
			(options
				(clearance outline)
				(anchor circle)
			)
			(primitives
				(gr_poly
					(pts
						(arc
							(start -0.254 0.1778)
							(mid -0.239121 0.213721)
							(end -0.2032 0.2286)
						)
						(arc
							(start 0.2032 0.2286)
							(mid 0.239121 0.213721)
							(end 0.254 0.1778)
						)
						(arc
							(start 0.254 -0.1778)
							(mid 0.239121 -0.213721)
							(end 0.2032 -0.2286)
						)
						(arc
							(start -0.2032 -0.2286)
							(mid -0.239121 -0.213721)
							(end -0.254 -0.1778)
						)
					)
					(width 0)
					(fill yes)
				)
			)
		)
		(pad "2" smd custom
			(at 0 0.4572 90)
			(size 0.1143 0.1143)
			(layers "B.Cu" "B.Mask" "B.Paste")
			(net "GND")
			(options
				(clearance outline)
				(anchor circle)
			)
			(primitives
				(gr_poly
					(pts
						(arc
							(start -0.254 0.1778)
							(mid -0.239121 0.213721)
							(end -0.2032 0.2286)
						)
						(arc
							(start 0.2032 0.2286)
							(mid 0.239121 0.213721)
							(end 0.254 0.1778)
						)
						(arc
							(start 0.254 -0.1778)
							(mid 0.239121 -0.213721)
							(end 0.2032 -0.2286)
						)
						(arc
							(start -0.2032 -0.2286)
							(mid -0.239121 -0.213721)
							(end -0.254 -0.1778)
						)
					)
					(width 0)
					(fill yes)
				)
			)
		)
	)
	(footprint ""
		(layer "B.Cu")
		(at 204.0128 -44.7548)
		(property "Reference" "PR104"
			(at 0 0 0)
			(layer "B.SilkS")
			(hide yes)
			(effects
				(font
					(size 1.27 1.27)
				)
				(justify mirror)
			)
		)
		(property "Value" "2D2R5F-2-GP"
			(at 0 -4.9022 0)
			(unlocked yes)
			(layer "B.Fab")
			(hide yes)
			(effects
				(font
					(size 1.016 1.016)
					(thickness 0.1524)
				)
				(justify mirror)
			)
		)
		(property "Device Type" "R805H24"
			(at 0 -6.8072 0)
			(unlocked yes)
			(layer "B.Fab")
			(hide yes)
			(effects
				(font
					(size 1.016 1.016)
					(thickness 0.1524)
				)
				(justify mirror)
			)
		)
		(duplicate_pad_numbers_are_jumpers no)
		(fp_line
			(start -0.6096 0)
			(end -0.2794 0)
			(stroke
				(width 0.3048)
				(type default)
			)
			(layer "B.SilkS")
		)
		(fp_line
			(start 0.2794 0)
			(end 0.6096 0)
			(stroke
				(width 0.3048)
				(type default)
			)
			(layer "B.SilkS")
		)
		(fp_poly
			(pts
				(xy 0.9017 1.4351) (xy -0.9017 1.4351) (xy -0.9017 -1.4351) (xy 0.9017 -1.4351)
			)
			(stroke
				(width 0)
				(type default)
			)
			(fill no)
			(layer "B.CrtYd")
		)
		(fp_poly
			(pts
				(xy -0.9017 1.4351) (xy -0.9017 -1.4351) (xy 0.9017 -1.4351) (xy 0.9017 1.4351)
			)
			(stroke
				(width 0)
				(type default)
			)
			(fill no)
			(layer "B.Fab")
		)
		(pad "1" smd rect
			(at 0 -0.8382 180)
			(size 1.5494 0.9398)
			(layers "B.Cu" "B.Mask" "B.Paste")
			(net "VR_PVDDR_A_VSW_R")
		)
		(pad "2" smd rect
			(at 0 0.8382 180)
			(size 1.5494 0.9398)
			(layers "B.Cu" "B.Mask" "B.Paste")
			(net "GND")
		)
	)
)
